(kicad_pcb
	(version 20260206)
	(generator "pcbnew")
	(generator_version "10.0")
	(general
		(thickness 1.6)
		(legacy_teardrops no)
	)
	(paper "A4")
	(title_block
		(title "12092022_DA0F0TMDCD0_F0T_Management_Board_D_brd_V3_OCP.brd")
		(comment 1 "Grand Teton / footprints 86-90 of 1440")
	)
	(layers
		(0 "F.Cu" signal "TOP")
		(4 "In1.Cu" signal "GND")
		(6 "In2.Cu" signal "IN1")
		(8 "In3.Cu" signal "GND1")
		(10 "In4.Cu" signal "IN2")
		(12 "In5.Cu" signal "VCC")
		(14 "In6.Cu" signal "VCC1")
		(16 "In7.Cu" signal "IN3")
		(18 "In8.Cu" signal "GND2")
		(20 "In9.Cu" signal "IN4")
		(22 "In10.Cu" signal "GND3")
		(2 "B.Cu" signal "BOTTOM")
		(9 "F.Adhes" user "F.Adhesive")
		(11 "B.Adhes" user "B.Adhesive")
		(13 "F.Paste" user "Package Geometry/Pastemask Top")
		(15 "B.Paste" user "Package Geometry/Pastemask Bottom")
		(5 "F.SilkS" user "Ref Des/Silkscreen Top")
		(7 "B.SilkS" user "Ref Des/Silkscreen Bottom")
		(1 "F.Mask" user "Board Geometry/Soldermask Top")
		(3 "B.Mask" user "Board Geometry/Soldermask Bottom")
		(17 "Dwgs.User" user "User.Drawings")
		(19 "Cmts.User" user "User.Comments")
		(21 "Eco1.User" user "User.Eco1")
		(23 "Eco2.User" user "User.Eco2")
		(25 "Edge.Cuts" user "Board Geometry/Outline")
		(27 "Margin" user)
		(31 "F.CrtYd" user "Package Geometry/Place Bound Top")
		(29 "B.CrtYd" user "Package Geometry/Place Bound Bottom")
		(35 "F.Fab" user "Ref Des/Assembly Top")
		(33 "B.Fab" user "Ref Des/Assembly Bottom")
	)
	(footprint ""
		(layer "F.Cu")
		(at 39.631112 -55.427626 90)
		(property "Reference" "R831"
			(at 0 0 90)
			(layer "F.SilkS")
			(hide yes)
			(effects
				(font
					(size 1.27 1.27)
				)
			)
		)
		(property "Value" ""
			(at 0 0 90)
			(layer "F.Fab")
			(effects
				(font
					(size 1.27 1.27)
				)
			)
		)
		(duplicate_pad_numbers_are_jumpers no)
		(fp_line
			(start 0.7874 -0.4064)
			(end 0.7874 0.4064)
			(stroke
				(width 0.1524)
				(type default)
			)
			(layer "F.SilkS")
		)
		(fp_line
			(start -0.7874 -0.4064)
			(end 0.7874 -0.4064)
			(stroke
				(width 0.1524)
				(type default)
			)
			(layer "F.SilkS")
		)
		(fp_line
			(start 0.7874 0.4064)
			(end -0.7874 0.4064)
			(stroke
				(width 0.1524)
				(type default)
			)
			(layer "F.SilkS")
		)
		(fp_line
			(start -0.7874 0.4064)
			(end -0.7874 -0.4064)
			(stroke
				(width 0.1524)
				(type default)
			)
			(layer "F.SilkS")
		)
		(fp_line
			(start -0.12065 -0.305054)
			(end -0.12065 -0.2794)
			(stroke
				(width 0.1)
				(type default)
			)
			(layer "F.Fab")
		)
		(fp_line
			(start -0.67945 -0.305054)
			(end -0.12065 -0.305054)
			(stroke
				(width 0.1)
				(type default)
			)
			(layer "F.Fab")
		)
		(fp_line
			(start 0.67945 -0.3048)
			(end 0.67945 0.3048)
			(stroke
				(width 0.1)
				(type default)
			)
			(layer "F.Fab")
		)
		(fp_line
			(start 0.12065 -0.3048)
			(end 0.67945 -0.3048)
			(stroke
				(width 0.1)
				(type default)
			)
			(layer "F.Fab")
		)
		(fp_line
			(start 0.12065 -0.2794)
			(end 0.12065 -0.3048)
			(stroke
				(width 0.1)
				(type default)
			)
			(layer "F.Fab")
		)
		(fp_line
			(start -0.12065 -0.2794)
			(end 0.12065 -0.2794)
			(stroke
				(width 0.1)
				(type default)
			)
			(layer "F.Fab")
		)
		(fp_line
			(start 0.120396 0.2794)
			(end -0.12065 0.2794)
			(stroke
				(width 0.1)
				(type default)
			)
			(layer "F.Fab")
		)
		(fp_line
			(start -0.12065 0.2794)
			(end -0.12065 0.3048)
			(stroke
				(width 0.1)
				(type default)
			)
			(layer "F.Fab")
		)
		(fp_line
			(start 0.67945 0.3048)
			(end 0.120396 0.3048)
			(stroke
				(width 0.1)
				(type default)
			)
			(layer "F.Fab")
		)
		(fp_line
			(start 0.120396 0.3048)
			(end 0.120396 0.2794)
			(stroke
				(width 0.1)
				(type default)
			)
			(layer "F.Fab")
		)
		(fp_line
			(start -0.12065 0.3048)
			(end -0.67945 0.3048)
			(stroke
				(width 0.1)
				(type default)
			)
			(layer "F.Fab")
		)
		(fp_line
			(start -0.67945 0.3048)
			(end -0.67945 -0.305054)
			(stroke
				(width 0.1)
				(type default)
			)
			(layer "F.Fab")
		)
		(pad "1" smd circle
			(at -0.40005 0 90)
			(size 0 0)
			(layers "F.Cu" "F.Mask" "F.Paste")
			(net "P1V8_AUX")
		)
		(pad "2" smd circle
			(at 0.40005 0 90)
			(size 0 0)
			(layers "F.Cu" "F.Mask" "F.Paste")
			(net "U41_ADJ")
		)
	)
	(footprint ""
		(layer "F.Cu")
		(at 51.6636 -109.3978 90)
		(property "Reference" "R161"
			(at 0 0 90)
			(layer "F.SilkS")
			(hide yes)
			(effects
				(font
					(size 1.27 1.27)
				)
			)
		)
		(property "Value" ""
			(at 0 0 90)
			(layer "F.Fab")
			(effects
				(font
					(size 1.27 1.27)
				)
			)
		)
		(duplicate_pad_numbers_are_jumpers no)
		(fp_line
			(start 0.7874 -0.4064)
			(end 0.7874 0.4064)
			(stroke
				(width 0.1524)
				(type default)
			)
			(layer "F.SilkS")
		)
		(fp_line
			(start -0.7874 -0.4064)
			(end 0.7874 -0.4064)
			(stroke
				(width 0.1524)
				(type default)
			)
			(layer "F.SilkS")
		)
		(fp_line
			(start 0.7874 0.4064)
			(end -0.7874 0.4064)
			(stroke
				(width 0.1524)
				(type default)
			)
			(layer "F.SilkS")
		)
		(fp_line
			(start -0.7874 0.4064)
			(end -0.7874 -0.4064)
			(stroke
				(width 0.1524)
				(type default)
			)
			(layer "F.SilkS")
		)
		(fp_line
			(start -0.12065 -0.305054)
			(end -0.12065 -0.2794)
			(stroke
				(width 0.1)
				(type default)
			)
			(layer "F.Fab")
		)
		(fp_line
			(start -0.67945 -0.305054)
			(end -0.12065 -0.305054)
			(stroke
				(width 0.1)
				(type default)
			)
			(layer "F.Fab")
		)
		(fp_line
			(start 0.67945 -0.3048)
			(end 0.67945 0.3048)
			(stroke
				(width 0.1)
				(type default)
			)
			(layer "F.Fab")
		)
		(fp_line
			(start 0.12065 -0.3048)
			(end 0.67945 -0.3048)
			(stroke
				(width 0.1)
				(type default)
			)
			(layer "F.Fab")
		)
		(fp_line
			(start 0.12065 -0.2794)
			(end 0.12065 -0.3048)
			(stroke
				(width 0.1)
				(type default)
			)
			(layer "F.Fab")
		)
		(fp_line
			(start -0.12065 -0.2794)
			(end 0.12065 -0.2794)
			(stroke
				(width 0.1)
				(type default)
			)
			(layer "F.Fab")
		)
		(fp_line
			(start 0.120396 0.2794)
			(end -0.12065 0.2794)
			(stroke
				(width 0.1)
				(type default)
			)
			(layer "F.Fab")
		)
		(fp_line
			(start -0.12065 0.2794)
			(end -0.12065 0.3048)
			(stroke
				(width 0.1)
				(type default)
			)
			(layer "F.Fab")
		)
		(fp_line
			(start 0.67945 0.3048)
			(end 0.120396 0.3048)
			(stroke
				(width 0.1)
				(type default)
			)
			(layer "F.Fab")
		)
		(fp_line
			(start 0.120396 0.3048)
			(end 0.120396 0.2794)
			(stroke
				(width 0.1)
				(type default)
			)
			(layer "F.Fab")
		)
		(fp_line
			(start -0.12065 0.3048)
			(end -0.67945 0.3048)
			(stroke
				(width 0.1)
				(type default)
			)
			(layer "F.Fab")
		)
		(fp_line
			(start -0.67945 0.3048)
			(end -0.67945 -0.305054)
			(stroke
				(width 0.1)
				(type default)
			)
			(layer "F.Fab")
		)
		(pad "1" smd circle
			(at -0.40005 0 90)
			(size 0 0)
			(layers "F.Cu" "F.Mask" "F.Paste")
			(net "P3V3_AUX")
		)
		(pad "2" smd circle
			(at 0.40005 0 90)
			(size 0 0)
			(layers "F.Cu" "F.Mask" "F.Paste")
			(net "RMII_CSRDV")
		)
	)
	(footprint ""
		(layer "F.Cu")
		(at 85.29955 -48.237394 180)
		(property "Reference" "R341"
			(at 0 0 180)
			(layer "F.SilkS")
			(hide yes)
			(effects
				(font
					(size 1.27 1.27)
				)
			)
		)
		(property "Value" ""
			(at 0 0 180)
			(layer "F.Fab")
			(effects
				(font
					(size 1.27 1.27)
				)
			)
		)
		(duplicate_pad_numbers_are_jumpers no)
		(fp_line
			(start 0.7874 0.4064)
			(end -0.7874 0.4064)
			(stroke
				(width 0.1524)
				(type default)
			)
			(layer "F.SilkS")
		)
		(fp_line
			(start 0.7874 -0.4064)
			(end 0.7874 0.4064)
			(stroke
				(width 0.1524)
				(type default)
			)
			(layer "F.SilkS")
		)
		(fp_line
			(start -0.7874 0.4064)
			(end -0.7874 -0.4064)
			(stroke
				(width 0.1524)
				(type default)
			)
			(layer "F.SilkS")
		)
		(fp_line
			(start -0.7874 -0.4064)
			(end 0.7874 -0.4064)
			(stroke
				(width 0.1524)
				(type default)
			)
			(layer "F.SilkS")
		)
		(fp_line
			(start 0.67945 0.3048)
			(end 0.120396 0.3048)
			(stroke
				(width 0.1)
				(type default)
			)
			(layer "F.Fab")
		)
		(fp_line
			(start 0.67945 -0.3048)
			(end 0.67945 0.3048)
			(stroke
				(width 0.1)
				(type default)
			)
			(layer "F.Fab")
		)
		(fp_line
			(start 0.12065 -0.2794)
			(end 0.12065 -0.3048)
			(stroke
				(width 0.1)
				(type default)
			)
			(layer "F.Fab")
		)
		(fp_line
			(start 0.12065 -0.3048)
			(end 0.67945 -0.3048)
			(stroke
				(width 0.1)
				(type default)
			)
			(layer "F.Fab")
		)
		(fp_line
			(start 0.120396 0.3048)
			(end 0.120396 0.2794)
			(stroke
				(width 0.1)
				(type default)
			)
			(layer "F.Fab")
		)
		(fp_line
			(start 0.120396 0.2794)
			(end -0.12065 0.2794)
			(stroke
				(width 0.1)
				(type default)
			)
			(layer "F.Fab")
		)
		(fp_line
			(start -0.12065 0.3048)
			(end -0.67945 0.3048)
			(stroke
				(width 0.1)
				(type default)
			)
			(layer "F.Fab")
		)
		(fp_line
			(start -0.12065 0.2794)
			(end -0.12065 0.3048)
			(stroke
				(width 0.1)
				(type default)
			)
			(layer "F.Fab")
		)
		(fp_line
			(start -0.12065 -0.2794)
			(end 0.12065 -0.2794)
			(stroke
				(width 0.1)
				(type default)
			)
			(layer "F.Fab")
		)
		(fp_line
			(start -0.12065 -0.305054)
			(end -0.12065 -0.2794)
			(stroke
				(width 0.1)
				(type default)
			)
			(layer "F.Fab")
		)
		(fp_line
			(start -0.67945 0.3048)
			(end -0.67945 -0.305054)
			(stroke
				(width 0.1)
				(type default)
			)
			(layer "F.Fab")
		)
		(fp_line
			(start -0.67945 -0.305054)
			(end -0.12065 -0.305054)
			(stroke
				(width 0.1)
				(type default)
			)
			(layer "F.Fab")
		)
		(pad "1" smd circle
			(at -0.40005 0 180)
			(size 0 0)
			(layers "F.Cu" "F.Mask" "F.Paste")
			(net "GND")
		)
		(pad "2" smd circle
			(at 0.40005 0 180)
			(size 0 0)
			(layers "F.Cu" "F.Mask" "F.Paste")
			(net "M_BMC_DDR4_MCAS_N")
		)
	)
	(footprint ""
		(layer "F.Cu")
		(at 39.42207 -13.379958)
		(property "Reference" "J2"
			(at -3.7719 -3.470148 0)
			(unlocked yes)
			(layer "F.SilkS")
			(effects
				(font
					(size 0.7874 0.5842)
					(thickness 0.1524)
				)
				(justify left)
			)
		)
		(property "Value" ""
			(at 0 0 0)
			(layer "F.Fab")
			(effects
				(font
					(size 1.27 1.27)
				)
			)
		)
		(duplicate_pad_numbers_are_jumpers no)
		(fp_line
			(start -3.700018 -1.952752)
			(end -3.700018 0.3175)
			(stroke
				(width 0.1524)
				(type default)
			)
			(layer "F.SilkS")
		)
		(fp_line
			(start -3.700018 3.683)
			(end -3.700018 13.780008)
			(stroke
				(width 0.1524)
				(type default)
			)
			(layer "F.SilkS")
		)
		(fp_line
			(start -3.700018 13.780008)
			(end 10.700004 13.780008)
			(stroke
				(width 0.1524)
				(type default)
			)
			(layer "F.SilkS")
		)
		(fp_line
			(start 0.350774 -2.720086)
			(end -2.489962 -2.720086)
			(stroke
				(width 0.1524)
				(type default)
			)
			(layer "F.SilkS")
		)
		(fp_line
			(start 3.49758 -2.720086)
			(end 2.034286 -2.720086)
			(stroke
				(width 0.1524)
				(type default)
			)
			(layer "F.SilkS")
		)
		(fp_line
			(start 10.700004 -2.720086)
			(end 6.785356 -2.720086)
			(stroke
				(width 0.1524)
				(type default)
			)
			(layer "F.SilkS")
		)
		(fp_line
			(start 10.700004 0.3175)
			(end 10.700004 -2.720086)
			(stroke
				(width 0.1524)
				(type default)
			)
			(layer "F.SilkS")
		)
		(fp_line
			(start 10.700004 13.780008)
			(end 10.700004 3.683)
			(stroke
				(width 0.1524)
				(type default)
			)
			(layer "F.SilkS")
		)
		(fp_poly
			(pts
				(xy -4.936998 0.508) (xy -4.936998 -0.508) (xy -3.920998 0)
			)
			(stroke
				(width 0)
				(type default)
			)
			(fill yes)
			(layer "F.SilkS")
		)
		(fp_line
			(start -3.700018 -2.720086)
			(end -3.700018 13.780008)
			(stroke
				(width 0.1)
				(type default)
			)
			(layer "F.Fab")
		)
		(fp_line
			(start -3.700018 13.780008)
			(end 10.700004 13.780008)
			(stroke
				(width 0.1)
				(type default)
			)
			(layer "F.Fab")
		)
		(fp_line
			(start 10.700004 -2.720086)
			(end -3.700018 -2.720086)
			(stroke
				(width 0.1)
				(type default)
			)
			(layer "F.Fab")
		)
		(fp_line
			(start 10.700004 13.780008)
			(end 10.700004 -2.720086)
			(stroke
				(width 0.1)
				(type default)
			)
			(layer "F.Fab")
		)
		(fp_poly
			(pts
				(xy -4.936998 0.508) (xy -4.936998 -0.508) (xy -3.920998 0)
			)
			(stroke
				(width 0)
				(type default)
			)
			(fill yes)
			(layer "F.Fab")
		)
		(pad "1" thru_hole rect
			(at 0 0 90)
			(size 1.1176 1.1176)
			(drill 0.7112)
			(layers "*.Cu" "*.Mask")
			(remove_unused_layers no)
			(net "P5V_USB_REAR")
			(clearance 0.0508)
			(thermal_gap 0.0508)
			(padstack
				(mode front_inner_back)
				(layer "Inner"
					(shape circle)
					(size 1.1176 1.1176)
					(clearance 0.0508)
				)
				(layer "B.Cu"
					(shape rect)
					(size 1.1176 1.1176)
					(clearance 0.0508)
				)
			)
		)
		(pad "2" thru_hole circle
			(at 2.500122 0 90)
			(size 1.1176 1.1176)
			(drill 0.7112)
			(layers "*.Cu" "*.Mask")
			(remove_unused_layers no)
			(net "USB2_01_F_DN")
			(clearance 0.0508)
			(thermal_gap 0.0508)
		)
		(pad "3" thru_hole circle
			(at 4.500118 0 90)
			(size 1.1176 1.1176)
			(drill 0.7112)
			(layers "*.Cu" "*.Mask")
			(remove_unused_layers no)
			(net "USB2_01_F_DP")
			(clearance 0.0508)
			(thermal_gap 0.0508)
		)
		(pad "4" thru_hole circle
			(at 6.999986 0 90)
			(size 1.1176 1.1176)
			(drill 0.7112)
			(layers "*.Cu" "*.Mask")
			(remove_unused_layers no)
			(net "GND")
			(clearance 0.0508)
			(thermal_gap 0.0508)
		)
		(pad "5" thru_hole circle
			(at 7.500112 -1.500124 90)
			(size 1.1176 1.1176)
			(drill 0.7112)
			(layers "*.Cu" "*.Mask")
			(remove_unused_layers no)
			(net "USB3_01_FB_RXN")
			(clearance 0.0508)
			(thermal_gap 0.0508)
		)
		(pad "6" thru_hole circle
			(at 5.500116 -1.500124 90)
			(size 1.1176 1.1176)
			(drill 0.7112)
			(layers "*.Cu" "*.Mask")
			(remove_unused_layers no)
			(net "USB3_01_FB_RXP")
			(clearance 0.0508)
			(thermal_gap 0.0508)
		)
		(pad "7" thru_hole circle
			(at 3.50012 -1.500124 90)
			(size 1.1176 1.1176)
			(drill 0.7112)
			(layers "*.Cu" "*.Mask")
			(remove_unused_layers no)
			(net "DEBUG_PORT_PRSNT_R")
			(clearance 0.0508)
			(thermal_gap 0.0508)
		)
		(pad "8" thru_hole circle
			(at 1.500124 -1.500124 90)
			(size 1.1176 1.1176)
			(drill 0.7112)
			(layers "*.Cu" "*.Mask")
			(remove_unused_layers no)
			(net "USB3_01_FB_TXN")
			(clearance 0.0508)
			(thermal_gap 0.0508)
		)
		(pad "9" thru_hole circle
			(at -0.499872 -1.500124 90)
			(size 1.1176 1.1176)
			(drill 0.7112)
			(layers "*.Cu" "*.Mask")
			(remove_unused_layers no)
			(net "USB3_01_FB_TXP")
			(clearance 0.0508)
			(thermal_gap 0.0508)
		)
		(pad "G1" thru_hole circle
			(at -3.070098 1.999996 90)
			(size 3.3274 3.3274)
			(drill 2.3114)
			(layers "*.Cu" "*.Mask")
			(remove_unused_layers no)
			(net "GND")
			(clearance -0.254)
		)
		(pad "G2" thru_hole circle
			(at 10.070084 1.999996 90)
			(size 3.3274 3.3274)
			(drill 2.3114)
			(layers "*.Cu" "*.Mask")
			(remove_unused_layers no)
			(net "GND")
			(clearance -0.254)
		)
	)
	(footprint ""
		(layer "F.Cu")
		(at 22.479 -102.743 -90)
		(property "Reference" "R746"
			(at 0 0 270)
			(layer "F.SilkS")
			(hide yes)
			(effects
				(font
					(size 1.27 1.27)
				)
			)
		)
		(property "Value" ""
			(at 0 0 270)
			(layer "F.Fab")
			(effects
				(font
					(size 1.27 1.27)
				)
			)
		)
		(duplicate_pad_numbers_are_jumpers no)
		(fp_line
			(start -0.7874 0.4064)
			(end -0.7874 -0.4064)
			(stroke
				(width 0.1524)
				(type default)
			)
			(layer "F.SilkS")
		)
		(fp_line
			(start 0.7874 0.4064)
			(end -0.7874 0.4064)
			(stroke
				(width 0.1524)
				(type default)
			)
			(layer "F.SilkS")
		)
		(fp_line
			(start -0.7874 -0.4064)
			(end 0.7874 -0.4064)
			(stroke
				(width 0.1524)
				(type default)
			)
			(layer "F.SilkS")
		)
		(fp_line
			(start 0.7874 -0.4064)
			(end 0.7874 0.4064)
			(stroke
				(width 0.1524)
				(type default)
			)
			(layer "F.SilkS")
		)
		(fp_line
			(start -0.67945 0.3048)
			(end -0.67945 -0.305054)
			(stroke
				(width 0.1)
				(type default)
			)
			(layer "F.Fab")
		)
		(fp_line
			(start -0.12065 0.3048)
			(end -0.67945 0.3048)
			(stroke
				(width 0.1)
				(type default)
			)
			(layer "F.Fab")
		)
		(fp_line
			(start 0.120396 0.3048)
			(end 0.120396 0.2794)
			(stroke
				(width 0.1)
				(type default)
			)
			(layer "F.Fab")
		)
		(fp_line
			(start 0.67945 0.3048)
			(end 0.120396 0.3048)
			(stroke
				(width 0.1)
				(type default)
			)
			(layer "F.Fab")
		)
		(fp_line
			(start -0.12065 0.2794)
			(end -0.12065 0.3048)
			(stroke
				(width 0.1)
				(type default)
			)
			(layer "F.Fab")
		)
		(fp_line
			(start 0.120396 0.2794)
			(end -0.12065 0.2794)
			(stroke
				(width 0.1)
				(type default)
			)
			(layer "F.Fab")
		)
		(fp_line
			(start -0.12065 -0.2794)
			(end 0.12065 -0.2794)
			(stroke
				(width 0.1)
				(type default)
			)
			(layer "F.Fab")
		)
		(fp_line
			(start 0.12065 -0.2794)
			(end 0.12065 -0.3048)
			(stroke
				(width 0.1)
				(type default)
			)
			(layer "F.Fab")
		)
		(fp_line
			(start 0.12065 -0.3048)
			(end 0.67945 -0.3048)
			(stroke
				(width 0.1)
				(type default)
			)
			(layer "F.Fab")
		)
		(fp_line
			(start 0.67945 -0.3048)
			(end 0.67945 0.3048)
			(stroke
				(width 0.1)
				(type default)
			)
			(layer "F.Fab")
		)
		(fp_line
			(start -0.67945 -0.305054)
			(end -0.12065 -0.305054)
			(stroke
				(width 0.1)
				(type default)
			)
			(layer "F.Fab")
		)
		(fp_line
			(start -0.12065 -0.305054)
			(end -0.12065 -0.2794)
			(stroke
				(width 0.1)
				(type default)
			)
			(layer "F.Fab")
		)
		(pad "1" smd circle
			(at -0.40005 0 270)
			(size 0 0)
			(layers "F.Cu" "F.Mask" "F.Paste")
			(net "IRQ_PCH_TPM_SPI_N")
		)
		(pad "2" smd circle
			(at 0.40005 0 270)
			(size 0 0)
			(layers "F.Cu" "F.Mask" "F.Paste")
			(net "IRQ_PCH_TPM_SPI_R2_N")
		)
	)
)
